# T6G (Grand Teton) — schematic netlist excerpt (pin names and nets, part order shuffled) for the footprints in the layout excerpt that follows; sources: Cadence DE-HDL packaged netlist, KiCad conversion of 04192023_DAF0TMB3IC0_F0TG_MB_C_brd_V02_OCP.brd

Q127  MOSFET_NCH_DUAL  PJT138K IC  pkg SOT363XD  page 146
  S1  = GND
  G1  = P12V_E1S_EN_0_R
  D2  = P12V_E1S_UV_0_R
  S2  = GND
  G2  = P12V_E1S_0_EN_G
  D1  = P12V_E1S_0_EN_G

PC480_2  Q_CAP  1UF 25V 10% X6S  pkg C0402  page 194 : A = SW_P12V_AUX_PVDDCR_CPU0_P0_FLT ; B = GND

(kicad_pcb
	(version 20260206)
	(generator "pcbnew")
	(generator_version "10.0")
	(general
		(thickness 1.6)
		(legacy_teardrops no)
	)
	(paper "A4")
	(title_block
		(title "04192023_DAF0TMB3IC0_F0TG_MB_C_brd_V02_OCP.brd")
		(comment 1 "Grand Teton / footprints 1136-1137 of 8354")
	)
	(layers
		(0 "F.Cu" signal "TOP")
		(4 "In1.Cu" signal "GND")
		(6 "In2.Cu" signal "IN1")
		(8 "In3.Cu" signal "GND1")
		(10 "In4.Cu" signal "IN2")
		(12 "In5.Cu" signal "GND2")
		(14 "In6.Cu" signal "IN3")
		(16 "In7.Cu" signal "GND3")
		(18 "In8.Cu" signal "VCC")
		(20 "In9.Cu" signal "VCC1")
		(22 "In10.Cu" signal "GND4")
		(24 "In11.Cu" signal "IN4")
		(26 "In12.Cu" signal "GND5")
		(28 "In13.Cu" signal "IN5")
		(30 "In14.Cu" signal "GND6")
		(32 "In15.Cu" signal "IN6")
		(34 "In16.Cu" signal "GND7")
		(2 "B.Cu" signal "BOTTOM")
		(9 "F.Adhes" user "F.Adhesive")
		(11 "B.Adhes" user "B.Adhesive")
		(13 "F.Paste" user "Package Geometry/Pastemask Top")
		(15 "B.Paste" user "Package Geometry/Pastemask Bottom")
		(5 "F.SilkS" user "Ref Des/Silkscreen Top")
		(7 "B.SilkS" user "Ref Des/Silkscreen Bottom")
		(1 "F.Mask" user "Board Geometry/Soldermask Top")
		(3 "B.Mask" user "Board Geometry/Soldermask Bottom")
		(17 "Dwgs.User" user "User.Drawings")
		(19 "Cmts.User" user "User.Comments")
		(21 "Eco1.User" user "User.Eco1")
		(23 "Eco2.User" user "User.Eco2")
		(25 "Edge.Cuts" user "Board Geometry/Outline")
		(27 "Margin" user)
		(31 "F.CrtYd" user "Package Geometry/Place Bound Top")
		(29 "B.CrtYd" user "Package Geometry/Place Bound Bottom")
		(35 "F.Fab" user "Ref Des/Assembly Top")
		(33 "B.Fab" user "Ref Des/Assembly Bottom")
	)
	(footprint ""
		(layer "F.Cu")
		(at 254.362966 -66.238374)
		(property "Reference" "Q127"
			(at -1.35382 1.881632 0)
			(unlocked yes)
			(layer "F.SilkS")
			(effects
				(font
					(size 0.7874 0.5842)
					(thickness 0.1524)
				)
				(justify left)
			)
		)
		(property "Value" ""
			(at 0 0 0)
			(layer "F.Fab")
			(effects
				(font
					(size 1.27 1.27)
				)
			)
		)
		(duplicate_pad_numbers_are_jumpers no)
		(fp_line
			(start -1.332738 -1.100074)
			(end -0.4826 -1.100074)
			(stroke
				(width 0.1524)
				(type default)
			)
			(layer "F.SilkS")
		)
		(fp_line
			(start -1.332738 1.100074)
			(end -1.332738 -1.100074)
			(stroke
				(width 0.1524)
				(type default)
			)
			(layer "F.SilkS")
		)
		(fp_line
			(start -0.4826 -1.100074)
			(end 0 -0.541274)
			(stroke
				(width 0.1524)
				(type default)
			)
			(layer "F.SilkS")
		)
		(fp_line
			(start 0 -0.541274)
			(end 0.4826 -1.100074)
			(stroke
				(width 0.1524)
				(type default)
			)
			(layer "F.SilkS")
		)
		(fp_line
			(start 0.4826 -1.100074)
			(end 1.332738 -1.100074)
			(stroke
				(width 0.1524)
				(type default)
			)
			(layer "F.SilkS")
		)
		(fp_line
			(start 1.332738 -1.100074)
			(end 1.332738 1.100074)
			(stroke
				(width 0.1524)
				(type default)
			)
			(layer "F.SilkS")
		)
		(fp_line
			(start 1.332738 1.100074)
			(end -1.332738 1.100074)
			(stroke
				(width 0.1524)
				(type default)
			)
			(layer "F.SilkS")
		)
		(fp_poly
			(pts
				(xy -1.909064 -0.755396) (xy -2.61112 -0.404368) (xy -2.61112 -1.106424)
			)
			(stroke
				(width 0)
				(type default)
			)
			(fill yes)
			(layer "F.SilkS")
		)
		(fp_line
			(start -0.674878 -1.100074)
			(end 0.674878 -1.100074)
			(stroke
				(width 0.1)
				(type default)
			)
			(layer "F.Fab")
		)
		(fp_line
			(start -0.674878 1.100074)
			(end -0.674878 -1.100074)
			(stroke
				(width 0.1)
				(type default)
			)
			(layer "F.Fab")
		)
		(fp_line
			(start 0.674878 -1.100074)
			(end 0.674878 1.100074)
			(stroke
				(width 0.1)
				(type default)
			)
			(layer "F.Fab")
		)
		(fp_line
			(start 0.674878 1.100074)
			(end -0.674878 1.100074)
			(stroke
				(width 0.1)
				(type default)
			)
			(layer "F.Fab")
		)
		(fp_poly
			(pts
				(xy -2.2352 -0.298958) (xy -2.2352 -1.001014) (xy -1.533144 -0.649986)
			)
			(stroke
				(width 0)
				(type default)
			)
			(fill yes)
			(layer "F.Fab")
		)
		(pad "1" smd rect
			(at -0.94996 -0.649986 90)
			(size 0.4318 0.508)
			(layers "F.Cu" "F.Mask" "F.Paste")
			(net "GND")
		)
		(pad "2" smd rect
			(at -0.94996 0 90)
			(size 0.4318 0.508)
			(layers "F.Cu" "F.Mask" "F.Paste")
			(net "P12V_E1S_EN_0_R")
		)
		(pad "3" smd rect
			(at -0.94996 0.649986 90)
			(size 0.4318 0.508)
			(layers "F.Cu" "F.Mask" "F.Paste")
			(net "P12V_E1S_UV_0_R")
		)
		(pad "4" smd rect
			(at 0.94996 0.649986 90)
			(size 0.4318 0.508)
			(layers "F.Cu" "F.Mask" "F.Paste")
			(net "GND")
		)
		(pad "5" smd rect
			(at 0.94996 0 90)
			(size 0.4318 0.508)
			(layers "F.Cu" "F.Mask" "F.Paste")
			(net "P12V_E1S_0_EN_G")
		)
		(pad "6" smd rect
			(at 0.94996 -0.649986 90)
			(size 0.4318 0.508)
			(layers "F.Cu" "F.Mask" "F.Paste")
			(net "P12V_E1S_0_EN_G")
		)
	)
	(footprint ""
		(layer "F.Cu")
		(at 369.00231 -182.602378 90)
		(property "Reference" "PC480_2"
			(at 0 0 90)
			(layer "F.SilkS")
			(hide yes)
			(effects
				(font
					(size 1.27 1.27)
				)
			)
		)
		(property "Value" ""
			(at 0 0 90)
			(layer "F.Fab")
			(effects
				(font
					(size 1.27 1.27)
				)
			)
		)
		(duplicate_pad_numbers_are_jumpers no)
		(fp_line
			(start 0.7874 -0.4064)
			(end 0.7874 0.4064)
			(stroke
				(width 0.1524)
				(type default)
			)
			(layer "F.SilkS")
		)
		(fp_line
			(start -0.7874 -0.4064)
			(end 0.7874 -0.4064)
			(stroke
				(width 0.1524)
				(type default)
			)
			(layer "F.SilkS")
		)
		(fp_line
			(start 0.7874 0.4064)
			(end -0.7874 0.4064)
			(stroke
				(width 0.1524)
				(type default)
			)
			(layer "F.SilkS")
		)
		(fp_line
			(start -0.7874 0.4064)
			(end -0.7874 -0.4064)
			(stroke
				(width 0.1524)
				(type default)
			)
			(layer "F.SilkS")
		)
		(fp_line
			(start -0.12065 -0.305054)
			(end -0.12065 -0.2794)
			(stroke
				(width 0.1)
				(type default)
			)
			(layer "F.Fab")
		)
		(fp_line
			(start -0.67945 -0.305054)
			(end -0.12065 -0.305054)
			(stroke
				(width 0.1)
				(type default)
			)
			(layer "F.Fab")
		)
		(fp_line
			(start 0.67945 -0.3048)
			(end 0.67945 0.3048)
			(stroke
				(width 0.1)
				(type default)
			)
			(layer "F.Fab")
		)
		(fp_line
			(start 0.12065 -0.3048)
			(end 0.67945 -0.3048)
			(stroke
				(width 0.1)
				(type default)
			)
			(layer "F.Fab")
		)
		(fp_line
			(start 0.12065 -0.2794)
			(end 0.12065 -0.3048)
			(stroke
				(width 0.1)
				(type default)
			)
			(layer "F.Fab")
		)
		(fp_line
			(start -0.12065 -0.2794)
			(end 0.12065 -0.2794)
			(stroke
				(width 0.1)
				(type default)
			)
			(layer "F.Fab")
		)
		(fp_line
			(start 0.120396 0.2794)
			(end -0.12065 0.2794)
			(stroke
				(width 0.1)
				(type default)
			)
			(layer "F.Fab")
		)
		(fp_line
			(start -0.12065 0.2794)
			(end -0.12065 0.3048)
			(stroke
				(width 0.1)
				(type default)
			)
			(layer "F.Fab")
		)
		(fp_line
			(start 0.67945 0.3048)
			(end 0.120396 0.3048)
			(stroke
				(width 0.1)
				(type default)
			)
			(layer "F.Fab")
		)
		(fp_line
			(start 0.120396 0.3048)
			(end 0.120396 0.2794)
			(stroke
				(width 0.1)
				(type default)
			)
			(layer "F.Fab")
		)
		(fp_line
			(start -0.12065 0.3048)
			(end -0.67945 0.3048)
			(stroke
				(width 0.1)
				(type default)
			)
			(layer "F.Fab")
		)
		(fp_line
			(start -0.67945 0.3048)
			(end -0.67945 -0.305054)
			(stroke
				(width 0.1)
				(type default)
			)
			(layer "F.Fab")
		)
		(pad "1" smd circle
			(at -0.40005 0 90)
			(size 0 0)
			(layers "F.Cu" "F.Mask" "F.Paste")
			(net "SW_P12V_AUX_PVDDCR_CPU0_P0_FLT")
		)
		(pad "2" smd circle
			(at 0.40005 0 90)
			(size 0 0)
			(layers "F.Cu" "F.Mask" "F.Paste")
			(net "GND")
		)
	)
)
